# S9S_MB_2U (Grand Teton) — schematic netlist excerpt (pin names and nets, part order shuffled) for the footprints in the layout excerpt that follows; sources: Cadence DE-HDL packaged netlist, KiCad conversion of 03242023_DA0F0TMBIJ0_F0T_Motherboard_J_brd_V01_OCP.brd

R4065  Q_RES  10K 1% EMPTY  pkg 0402LF  page 162 : A = P12V_AUX ; B = P12V_OCP_2_EN_G
PC1260  Q_CAP  22UF 16V 20% X6S  pkg C0805  page 299 : A = SW_P12V_PVCCIN_CPU1_FLT ; B = GND
PC1642  Q_CAP  1UF 25V 10% X6S  pkg C0402  page 263 : A = P1V8_PCH_AUX_VCC ; B = GND

(kicad_pcb
	(version 20260206)
	(generator "pcbnew")
	(generator_version "10.0")
	(general
		(thickness 1.6)
		(legacy_teardrops no)
	)
	(paper "A4")
	(title_block
		(title "03242023_DA0F0TMBIJ0_F0T_Motherboard_J_brd_V01_OCP.brd")
		(comment 1 "Grand Teton / footprints 409-411 of 6105")
	)
	(layers
		(0 "F.Cu" signal "TOP")
		(4 "In1.Cu" signal "GND")
		(6 "In2.Cu" signal "IN1")
		(8 "In3.Cu" signal "GND1")
		(10 "In4.Cu" signal "IN2")
		(12 "In5.Cu" signal "GND2")
		(14 "In6.Cu" signal "IN3")
		(16 "In7.Cu" signal "GND3")
		(18 "In8.Cu" signal "VCC")
		(20 "In9.Cu" signal "VCC1")
		(22 "In10.Cu" signal "GND4")
		(24 "In11.Cu" signal "IN4")
		(26 "In12.Cu" signal "GND5")
		(28 "In13.Cu" signal "IN5")
		(30 "In14.Cu" signal "GND6")
		(32 "In15.Cu" signal "IN6")
		(34 "In16.Cu" signal "GND7")
		(2 "B.Cu" signal "BOTTOM")
		(9 "F.Adhes" user "F.Adhesive")
		(11 "B.Adhes" user "B.Adhesive")
		(13 "F.Paste" user "Package Geometry/Pastemask Top")
		(15 "B.Paste" user "Package Geometry/Pastemask Bottom")
		(5 "F.SilkS" user "Ref Des/Silkscreen Top")
		(7 "B.SilkS" user "Ref Des/Silkscreen Bottom")
		(1 "F.Mask" user "Board Geometry/Soldermask Top")
		(3 "B.Mask" user "Board Geometry/Soldermask Bottom")
		(17 "Dwgs.User" user "User.Drawings")
		(19 "Cmts.User" user "User.Comments")
		(21 "Eco1.User" user "User.Eco1")
		(23 "Eco2.User" user "User.Eco2")
		(25 "Edge.Cuts" user "Board Geometry/Outline")
		(27 "Margin" user)
		(31 "F.CrtYd" user "Package Geometry/Place Bound Top")
		(29 "B.CrtYd" user "Package Geometry/Place Bound Bottom")
		(35 "F.Fab" user "Ref Des/Assembly Top")
		(33 "B.Fab" user "Ref Des/Assembly Bottom")
	)
	(footprint ""
		(layer "F.Cu")
		(at 383.514854 -73.15962)
		(property "Reference" "PC1642"
			(at 0 0 0)
			(layer "F.SilkS")
			(hide yes)
			(effects
				(font
					(size 1.27 1.27)
				)
			)
		)
		(property "Value" ""
			(at 0 0 0)
			(layer "F.Fab")
			(effects
				(font
					(size 1.27 1.27)
				)
			)
		)
		(duplicate_pad_numbers_are_jumpers no)
		(fp_line
			(start -0.7874 -0.4064)
			(end 0.7874 -0.4064)
			(stroke
				(width 0.1524)
				(type default)
			)
			(layer "F.SilkS")
		)
		(fp_line
			(start -0.7874 0.4064)
			(end -0.7874 -0.4064)
			(stroke
				(width 0.1524)
				(type default)
			)
			(layer "F.SilkS")
		)
		(fp_line
			(start 0.7874 -0.4064)
			(end 0.7874 0.4064)
			(stroke
				(width 0.1524)
				(type default)
			)
			(layer "F.SilkS")
		)
		(fp_line
			(start 0.7874 0.4064)
			(end -0.7874 0.4064)
			(stroke
				(width 0.1524)
				(type default)
			)
			(layer "F.SilkS")
		)
		(fp_line
			(start -0.67945 -0.305054)
			(end -0.12065 -0.305054)
			(stroke
				(width 0.1)
				(type default)
			)
			(layer "F.Fab")
		)
		(fp_line
			(start -0.67945 0.3048)
			(end -0.67945 -0.305054)
			(stroke
				(width 0.1)
				(type default)
			)
			(layer "F.Fab")
		)
		(fp_line
			(start -0.12065 -0.305054)
			(end -0.12065 -0.2794)
			(stroke
				(width 0.1)
				(type default)
			)
			(layer "F.Fab")
		)
		(fp_line
			(start -0.12065 -0.2794)
			(end 0.12065 -0.2794)
			(stroke
				(width 0.1)
				(type default)
			)
			(layer "F.Fab")
		)
		(fp_line
			(start -0.12065 0.2794)
			(end -0.12065 0.3048)
			(stroke
				(width 0.1)
				(type default)
			)
			(layer "F.Fab")
		)
		(fp_line
			(start -0.12065 0.3048)
			(end -0.67945 0.3048)
			(stroke
				(width 0.1)
				(type default)
			)
			(layer "F.Fab")
		)
		(fp_line
			(start 0.120396 0.2794)
			(end -0.12065 0.2794)
			(stroke
				(width 0.1)
				(type default)
			)
			(layer "F.Fab")
		)
		(fp_line
			(start 0.120396 0.3048)
			(end 0.120396 0.2794)
			(stroke
				(width 0.1)
				(type default)
			)
			(layer "F.Fab")
		)
		(fp_line
			(start 0.12065 -0.3048)
			(end 0.67945 -0.3048)
			(stroke
				(width 0.1)
				(type default)
			)
			(layer "F.Fab")
		)
		(fp_line
			(start 0.12065 -0.2794)
			(end 0.12065 -0.3048)
			(stroke
				(width 0.1)
				(type default)
			)
			(layer "F.Fab")
		)
		(fp_line
			(start 0.67945 -0.3048)
			(end 0.67945 0.3048)
			(stroke
				(width 0.1)
				(type default)
			)
			(layer "F.Fab")
		)
		(fp_line
			(start 0.67945 0.3048)
			(end 0.120396 0.3048)
			(stroke
				(width 0.1)
				(type default)
			)
			(layer "F.Fab")
		)
		(pad "1" smd circle
			(at -0.40005 0)
			(size 0 0)
			(layers "F.Cu" "F.Mask" "F.Paste")
			(net "P1V8_PCH_AUX_VCC")
		)
		(pad "2" smd circle
			(at 0.40005 0)
			(size 0 0)
			(layers "F.Cu" "F.Mask" "F.Paste")
			(net "GND")
		)
	)
	(footprint ""
		(layer "F.Cu")
		(at 126.396242 -352.812858)
		(property "Reference" "PC1260"
			(at 0 0 0)
			(layer "F.SilkS")
			(hide yes)
			(effects
				(font
					(size 1.27 1.27)
				)
			)
		)
		(property "Value" ""
			(at 0 0 0)
			(layer "F.Fab")
			(effects
				(font
					(size 1.27 1.27)
				)
			)
		)
		(duplicate_pad_numbers_are_jumpers no)
		(fp_line
			(start -1.524 -0.762)
			(end 1.524 -0.762)
			(stroke
				(width 0.1524)
				(type default)
			)
			(layer "F.SilkS")
		)
		(fp_line
			(start -1.524 0.762)
			(end -1.524 -0.762)
			(stroke
				(width 0.1524)
				(type default)
			)
			(layer "F.SilkS")
		)
		(fp_line
			(start 1.524 -0.762)
			(end 1.524 0.762)
			(stroke
				(width 0.1524)
				(type default)
			)
			(layer "F.SilkS")
		)
		(fp_line
			(start 1.524 0.762)
			(end -1.524 0.762)
			(stroke
				(width 0.1524)
				(type default)
			)
			(layer "F.SilkS")
		)
		(fp_line
			(start -1.1049 -0.724916)
			(end -1.1049 0.724916)
			(stroke
				(width 0.1)
				(type default)
			)
			(layer "F.Fab")
		)
		(fp_line
			(start -1.1049 0.724916)
			(end 1.1049 0.724916)
			(stroke
				(width 0.1)
				(type default)
			)
			(layer "F.Fab")
		)
		(fp_line
			(start 1.1049 -0.724916)
			(end -1.1049 -0.724916)
			(stroke
				(width 0.1)
				(type default)
			)
			(layer "F.Fab")
		)
		(fp_line
			(start 1.1049 0.724916)
			(end 1.1049 -0.724916)
			(stroke
				(width 0.1)
				(type default)
			)
			(layer "F.Fab")
		)
		(pad "1" smd rect
			(at -0.889 0 180)
			(size 1.016 1.27)
			(layers "F.Cu" "F.Mask" "F.Paste")
			(net "SW_P12V_PVCCIN_CPU1_FLT")
		)
		(pad "2" smd rect
			(at 0.889 0 180)
			(size 1.016 1.27)
			(layers "F.Cu" "F.Mask" "F.Paste")
			(net "GND")
		)
	)
	(footprint ""
		(layer "F.Cu")
		(at 59.8678 -36.083748 180)
		(property "Reference" "R4065"
			(at 0 0 180)
			(layer "F.SilkS")
			(hide yes)
			(effects
				(font
					(size 1.27 1.27)
				)
			)
		)
		(property "Value" ""
			(at 0 0 180)
			(layer "F.Fab")
			(effects
				(font
					(size 1.27 1.27)
				)
			)
		)
		(duplicate_pad_numbers_are_jumpers no)
		(fp_line
			(start 0.7874 0.4064)
			(end -0.7874 0.4064)
			(stroke
				(width 0.1524)
				(type default)
			)
			(layer "F.SilkS")
		)
		(fp_line
			(start 0.7874 -0.4064)
			(end 0.7874 0.4064)
			(stroke
				(width 0.1524)
				(type default)
			)
			(layer "F.SilkS")
		)
		(fp_line
			(start -0.7874 0.4064)
			(end -0.7874 -0.4064)
			(stroke
				(width 0.1524)
				(type default)
			)
			(layer "F.SilkS")
		)
		(fp_line
			(start -0.7874 -0.4064)
			(end 0.7874 -0.4064)
			(stroke
				(width 0.1524)
				(type default)
			)
			(layer "F.SilkS")
		)
		(fp_line
			(start 0.67945 0.3048)
			(end 0.120396 0.3048)
			(stroke
				(width 0.1)
				(type default)
			)
			(layer "F.Fab")
		)
		(fp_line
			(start 0.67945 -0.3048)
			(end 0.67945 0.3048)
			(stroke
				(width 0.1)
				(type default)
			)
			(layer "F.Fab")
		)
		(fp_line
			(start 0.12065 -0.2794)
			(end 0.12065 -0.3048)
			(stroke
				(width 0.1)
				(type default)
			)
			(layer "F.Fab")
		)
		(fp_line
			(start 0.12065 -0.3048)
			(end 0.67945 -0.3048)
			(stroke
				(width 0.1)
				(type default)
			)
			(layer "F.Fab")
		)
		(fp_line
			(start 0.120396 0.3048)
			(end 0.120396 0.2794)
			(stroke
				(width 0.1)
				(type default)
			)
			(layer "F.Fab")
		)
		(fp_line
			(start 0.120396 0.2794)
			(end -0.12065 0.2794)
			(stroke
				(width 0.1)
				(type default)
			)
			(layer "F.Fab")
		)
		(fp_line
			(start -0.12065 0.3048)
			(end -0.67945 0.3048)
			(stroke
				(width 0.1)
				(type default)
			)
			(layer "F.Fab")
		)
		(fp_line
			(start -0.12065 0.2794)
			(end -0.12065 0.3048)
			(stroke
				(width 0.1)
				(type default)
			)
			(layer "F.Fab")
		)
		(fp_line
			(start -0.12065 -0.2794)
			(end 0.12065 -0.2794)
			(stroke
				(width 0.1)
				(type default)
			)
			(layer "F.Fab")
		)
		(fp_line
			(start -0.12065 -0.305054)
			(end -0.12065 -0.2794)
			(stroke
				(width 0.1)
				(type default)
			)
			(layer "F.Fab")
		)
		(fp_line
			(start -0.67945 0.3048)
			(end -0.67945 -0.305054)
			(stroke
				(width 0.1)
				(type default)
			)
			(layer "F.Fab")
		)
		(fp_line
			(start -0.67945 -0.305054)
			(end -0.12065 -0.305054)
			(stroke
				(width 0.1)
				(type default)
			)
			(layer "F.Fab")
		)
		(pad "1" smd circle
			(at -0.40005 0 180)
			(size 0 0)
			(layers "F.Cu" "F.Mask" "F.Paste")
			(net "P12V_AUX")
		)
		(pad "2" smd circle
			(at 0.40005 0 180)
			(size 0 0)
			(layers "F.Cu" "F.Mask" "F.Paste")
			(net "P12V_OCP_2_EN_G")
		)
	)
)
